# T6G (Grand Teton) — schematic netlist excerpt (pin names and nets, part order shuffled) for the footprints in the layout excerpt that follows; sources: Cadence DE-HDL packaged netlist, KiCad conversion of 04192023_DAF0TMB3IC0_F0TG_MB_C_brd_V02_OCP.brd

R3283  Q_RES  1K 1% EMPTY  pkg 0402LF  page 111 : A = P3V3_AUX ; B = FM_P2E_EQB0
C1112  Q_CAP  0.1UF 25V 10% X7R  pkg 0402  page 357 : A = VSENSE_P12V_INA230_7_INP ; B = VSENSE_P12V_INA230_7_INN
R1480  Q_RES  10 1% EMPTY  pkg 2512LF  page 169 : A = P12V_AUX ; B = P12V_AUX_DSC

(kicad_pcb
	(version 20260206)
	(generator "pcbnew")
	(generator_version "10.0")
	(general
		(thickness 1.6)
		(legacy_teardrops no)
	)
	(paper "A4")
	(title_block
		(title "04192023_DAF0TMB3IC0_F0TG_MB_C_brd_V02_OCP.brd")
		(comment 1 "Grand Teton / footprints 4224-4226 of 8354")
	)
	(layers
		(0 "F.Cu" signal "TOP")
		(4 "In1.Cu" signal "GND")
		(6 "In2.Cu" signal "IN1")
		(8 "In3.Cu" signal "GND1")
		(10 "In4.Cu" signal "IN2")
		(12 "In5.Cu" signal "GND2")
		(14 "In6.Cu" signal "IN3")
		(16 "In7.Cu" signal "GND3")
		(18 "In8.Cu" signal "VCC")
		(20 "In9.Cu" signal "VCC1")
		(22 "In10.Cu" signal "GND4")
		(24 "In11.Cu" signal "IN4")
		(26 "In12.Cu" signal "GND5")
		(28 "In13.Cu" signal "IN5")
		(30 "In14.Cu" signal "GND6")
		(32 "In15.Cu" signal "IN6")
		(34 "In16.Cu" signal "GND7")
		(2 "B.Cu" signal "BOTTOM")
		(9 "F.Adhes" user "F.Adhesive")
		(11 "B.Adhes" user "B.Adhesive")
		(13 "F.Paste" user "Package Geometry/Pastemask Top")
		(15 "B.Paste" user "Package Geometry/Pastemask Bottom")
		(5 "F.SilkS" user "Ref Des/Silkscreen Top")
		(7 "B.SilkS" user "Ref Des/Silkscreen Bottom")
		(1 "F.Mask" user "Board Geometry/Soldermask Top")
		(3 "B.Mask" user "Board Geometry/Soldermask Bottom")
		(17 "Dwgs.User" user "User.Drawings")
		(19 "Cmts.User" user "User.Comments")
		(21 "Eco1.User" user "User.Eco1")
		(23 "Eco2.User" user "User.Eco2")
		(25 "Edge.Cuts" user "Board Geometry/Outline")
		(27 "Margin" user)
		(31 "F.CrtYd" user "Package Geometry/Place Bound Top")
		(29 "B.CrtYd" user "Package Geometry/Place Bound Bottom")
		(35 "F.Fab" user "Ref Des/Assembly Top")
		(33 "B.Fab" user "Ref Des/Assembly Bottom")
	)
	(footprint ""
		(layer "F.Cu")
		(at 37.41166 -125.38202 -90)
		(property "Reference" "R1480"
			(at -0.17526 -2.686812 90)
			(unlocked yes)
			(layer "F.SilkS")
			(effects
				(font
					(size 0.7874 0.5842)
					(thickness 0.1524)
				)
				(justify left)
			)
		)
		(property "Value" ""
			(at 0 0 270)
			(layer "F.Fab")
			(effects
				(font
					(size 1.27 1.27)
				)
			)
		)
		(duplicate_pad_numbers_are_jumpers no)
		(fp_line
			(start -4.18973 1.700022)
			(end 4.18973 1.700022)
			(stroke
				(width 0.1524)
				(type default)
			)
			(layer "F.SilkS")
		)
		(fp_line
			(start 4.18973 1.700022)
			(end 4.18973 -1.700022)
			(stroke
				(width 0.1524)
				(type default)
			)
			(layer "F.SilkS")
		)
		(fp_line
			(start -4.18973 -1.700022)
			(end -4.18973 1.700022)
			(stroke
				(width 0.1524)
				(type default)
			)
			(layer "F.SilkS")
		)
		(fp_line
			(start 4.18973 -1.700022)
			(end -4.18973 -1.700022)
			(stroke
				(width 0.1524)
				(type default)
			)
			(layer "F.SilkS")
		)
		(fp_line
			(start -3.24993 1.700022)
			(end 3.24993 1.700022)
			(stroke
				(width 0.1)
				(type default)
			)
			(layer "F.Fab")
		)
		(fp_line
			(start 3.24993 1.700022)
			(end 3.24993 -1.700022)
			(stroke
				(width 0.1)
				(type default)
			)
			(layer "F.Fab")
		)
		(fp_line
			(start -3.24993 -1.700022)
			(end -3.24993 1.700022)
			(stroke
				(width 0.1)
				(type default)
			)
			(layer "F.Fab")
		)
		(fp_line
			(start 3.24993 -1.700022)
			(end -3.24993 -1.700022)
			(stroke
				(width 0.1)
				(type default)
			)
			(layer "F.Fab")
		)
		(pad "1" smd rect
			(at -2.975102 0 270)
			(size 2.159 2.921)
			(layers "F.Cu" "F.Mask" "F.Paste")
			(net "P12V_AUX")
		)
		(pad "2" smd rect
			(at 2.975102 0 270)
			(size 2.159 2.921)
			(layers "F.Cu" "F.Mask" "F.Paste")
			(net "P12V_AUX_DSC")
		)
	)
	(footprint ""
		(layer "F.Cu")
		(at 29.045662 -425.275502)
		(property "Reference" "R3283"
			(at 0 0 0)
			(layer "F.SilkS")
			(hide yes)
			(effects
				(font
					(size 1.27 1.27)
				)
			)
		)
		(property "Value" ""
			(at 0 0 0)
			(layer "F.Fab")
			(effects
				(font
					(size 1.27 1.27)
				)
			)
		)
		(duplicate_pad_numbers_are_jumpers no)
		(fp_line
			(start -0.7874 -0.4064)
			(end 0.7874 -0.4064)
			(stroke
				(width 0.1524)
				(type default)
			)
			(layer "F.SilkS")
		)
		(fp_line
			(start -0.7874 0.4064)
			(end -0.7874 -0.4064)
			(stroke
				(width 0.1524)
				(type default)
			)
			(layer "F.SilkS")
		)
		(fp_line
			(start 0.7874 -0.4064)
			(end 0.7874 0.4064)
			(stroke
				(width 0.1524)
				(type default)
			)
			(layer "F.SilkS")
		)
		(fp_line
			(start 0.7874 0.4064)
			(end -0.7874 0.4064)
			(stroke
				(width 0.1524)
				(type default)
			)
			(layer "F.SilkS")
		)
		(fp_line
			(start -0.67945 -0.305054)
			(end -0.12065 -0.305054)
			(stroke
				(width 0.1)
				(type default)
			)
			(layer "F.Fab")
		)
		(fp_line
			(start -0.67945 0.3048)
			(end -0.67945 -0.305054)
			(stroke
				(width 0.1)
				(type default)
			)
			(layer "F.Fab")
		)
		(fp_line
			(start -0.12065 -0.305054)
			(end -0.12065 -0.2794)
			(stroke
				(width 0.1)
				(type default)
			)
			(layer "F.Fab")
		)
		(fp_line
			(start -0.12065 -0.2794)
			(end 0.12065 -0.2794)
			(stroke
				(width 0.1)
				(type default)
			)
			(layer "F.Fab")
		)
		(fp_line
			(start -0.12065 0.2794)
			(end -0.12065 0.3048)
			(stroke
				(width 0.1)
				(type default)
			)
			(layer "F.Fab")
		)
		(fp_line
			(start -0.12065 0.3048)
			(end -0.67945 0.3048)
			(stroke
				(width 0.1)
				(type default)
			)
			(layer "F.Fab")
		)
		(fp_line
			(start 0.120396 0.2794)
			(end -0.12065 0.2794)
			(stroke
				(width 0.1)
				(type default)
			)
			(layer "F.Fab")
		)
		(fp_line
			(start 0.120396 0.3048)
			(end 0.120396 0.2794)
			(stroke
				(width 0.1)
				(type default)
			)
			(layer "F.Fab")
		)
		(fp_line
			(start 0.12065 -0.3048)
			(end 0.67945 -0.3048)
			(stroke
				(width 0.1)
				(type default)
			)
			(layer "F.Fab")
		)
		(fp_line
			(start 0.12065 -0.2794)
			(end 0.12065 -0.3048)
			(stroke
				(width 0.1)
				(type default)
			)
			(layer "F.Fab")
		)
		(fp_line
			(start 0.67945 -0.3048)
			(end 0.67945 0.3048)
			(stroke
				(width 0.1)
				(type default)
			)
			(layer "F.Fab")
		)
		(fp_line
			(start 0.67945 0.3048)
			(end 0.120396 0.3048)
			(stroke
				(width 0.1)
				(type default)
			)
			(layer "F.Fab")
		)
		(pad "1" smd circle
			(at -0.40005 0)
			(size 0 0)
			(layers "F.Cu" "F.Mask" "F.Paste")
			(net "P3V3_AUX")
		)
		(pad "2" smd circle
			(at 0.40005 0)
			(size 0 0)
			(layers "F.Cu" "F.Mask" "F.Paste")
			(net "FM_P2E_EQB0")
		)
	)
	(footprint ""
		(layer "F.Cu")
		(at 70.346824 -19.929094 180)
		(property "Reference" "C1112"
			(at 0 0 180)
			(layer "F.SilkS")
			(hide yes)
			(effects
				(font
					(size 1.27 1.27)
				)
			)
		)
		(property "Value" ""
			(at 0 0 180)
			(layer "F.Fab")
			(effects
				(font
					(size 1.27 1.27)
				)
			)
		)
		(duplicate_pad_numbers_are_jumpers no)
		(fp_line
			(start 0.7874 0.4064)
			(end -0.7874 0.4064)
			(stroke
				(width 0.1524)
				(type default)
			)
			(layer "F.SilkS")
		)
		(fp_line
			(start 0.7874 -0.4064)
			(end 0.7874 0.4064)
			(stroke
				(width 0.1524)
				(type default)
			)
			(layer "F.SilkS")
		)
		(fp_line
			(start -0.7874 0.4064)
			(end -0.7874 -0.4064)
			(stroke
				(width 0.1524)
				(type default)
			)
			(layer "F.SilkS")
		)
		(fp_line
			(start -0.7874 -0.4064)
			(end 0.7874 -0.4064)
			(stroke
				(width 0.1524)
				(type default)
			)
			(layer "F.SilkS")
		)
		(fp_line
			(start 0.67945 0.3048)
			(end 0.120396 0.3048)
			(stroke
				(width 0.1)
				(type default)
			)
			(layer "F.Fab")
		)
		(fp_line
			(start 0.67945 -0.3048)
			(end 0.67945 0.3048)
			(stroke
				(width 0.1)
				(type default)
			)
			(layer "F.Fab")
		)
		(fp_line
			(start 0.12065 -0.2794)
			(end 0.12065 -0.3048)
			(stroke
				(width 0.1)
				(type default)
			)
			(layer "F.Fab")
		)
		(fp_line
			(start 0.12065 -0.3048)
			(end 0.67945 -0.3048)
			(stroke
				(width 0.1)
				(type default)
			)
			(layer "F.Fab")
		)
		(fp_line
			(start 0.120396 0.3048)
			(end 0.120396 0.2794)
			(stroke
				(width 0.1)
				(type default)
			)
			(layer "F.Fab")
		)
		(fp_line
			(start 0.120396 0.2794)
			(end -0.12065 0.2794)
			(stroke
				(width 0.1)
				(type default)
			)
			(layer "F.Fab")
		)
		(fp_line
			(start -0.12065 0.3048)
			(end -0.67945 0.3048)
			(stroke
				(width 0.1)
				(type default)
			)
			(layer "F.Fab")
		)
		(fp_line
			(start -0.12065 0.2794)
			(end -0.12065 0.3048)
			(stroke
				(width 0.1)
				(type default)
			)
			(layer "F.Fab")
		)
		(fp_line
			(start -0.12065 -0.2794)
			(end 0.12065 -0.2794)
			(stroke
				(width 0.1)
				(type default)
			)
			(layer "F.Fab")
		)
		(fp_line
			(start -0.12065 -0.305054)
			(end -0.12065 -0.2794)
			(stroke
				(width 0.1)
				(type default)
			)
			(layer "F.Fab")
		)
		(fp_line
			(start -0.67945 0.3048)
			(end -0.67945 -0.305054)
			(stroke
				(width 0.1)
				(type default)
			)
			(layer "F.Fab")
		)
		(fp_line
			(start -0.67945 -0.305054)
			(end -0.12065 -0.305054)
			(stroke
				(width 0.1)
				(type default)
			)
			(layer "F.Fab")
		)
		(pad "1" smd circle
			(at -0.40005 0 180)
			(size 0 0)
			(layers "F.Cu" "F.Mask" "F.Paste")
			(net "VSENSE_P12V_INA230_7_INP")
		)
		(pad "2" smd circle
			(at 0.40005 0 180)
			(size 0 0)
			(layers "F.Cu" "F.Mask" "F.Paste")
			(net "VSENSE_P12V_INA230_7_INN")
		)
	)
)
